# SCM (Grand Teton) — schematic netlist excerpt (pin names and nets, part order shuffled) for the footprints in the layout excerpt that follows; sources: Cadence DE-HDL packaged netlist, KiCad conversion of 12092022_DA0F0TMDCD0_F0T_Management_Board_D_brd_V3_OCP.brd

J2  CONN9_GSB3111315HR  IO  pkg USB1XBH  page 29
  VBUS  = P5V_USB_REAR
  \d-\  = USB2_01_F_DN
  \d+\  = USB2_01_F_DP
  GND  = GND
  \ssrx-\  = USB3_01_FB_RXN
  \ssrx+\  = USB3_01_FB_RXP
  GND_D  = DEBUG_PORT_PRSNT_R
  \sstx-\  = USB3_01_FB_TXN
  \sstx+\  = USB3_01_FB_TXP
  G1  = GND
  G2  = GND

(kicad_pcb
	(version 20260206)
	(generator "pcbnew")
	(generator_version "10.0")
	(general
		(thickness 1.6)
		(legacy_teardrops no)
	)
	(paper "A4")
	(title_block
		(title "12092022_DA0F0TMDCD0_F0T_Management_Board_D_brd_V3_OCP.brd")
		(comment 1 "Grand Teton / footprints 89-89 of 1440")
	)
	(layers
		(0 "F.Cu" signal "TOP")
		(4 "In1.Cu" signal "GND")
		(6 "In2.Cu" signal "IN1")
		(8 "In3.Cu" signal "GND1")
		(10 "In4.Cu" signal "IN2")
		(12 "In5.Cu" signal "VCC")
		(14 "In6.Cu" signal "VCC1")
		(16 "In7.Cu" signal "IN3")
		(18 "In8.Cu" signal "GND2")
		(20 "In9.Cu" signal "IN4")
		(22 "In10.Cu" signal "GND3")
		(2 "B.Cu" signal "BOTTOM")
		(9 "F.Adhes" user "F.Adhesive")
		(11 "B.Adhes" user "B.Adhesive")
		(13 "F.Paste" user "Package Geometry/Pastemask Top")
		(15 "B.Paste" user "Package Geometry/Pastemask Bottom")
		(5 "F.SilkS" user "Ref Des/Silkscreen Top")
		(7 "B.SilkS" user "Ref Des/Silkscreen Bottom")
		(1 "F.Mask" user "Board Geometry/Soldermask Top")
		(3 "B.Mask" user "Board Geometry/Soldermask Bottom")
		(17 "Dwgs.User" user "User.Drawings")
		(19 "Cmts.User" user "User.Comments")
		(21 "Eco1.User" user "User.Eco1")
		(23 "Eco2.User" user "User.Eco2")
		(25 "Edge.Cuts" user "Board Geometry/Outline")
		(27 "Margin" user)
		(31 "F.CrtYd" user "Package Geometry/Place Bound Top")
		(29 "B.CrtYd" user "Package Geometry/Place Bound Bottom")
		(35 "F.Fab" user "Ref Des/Assembly Top")
		(33 "B.Fab" user "Ref Des/Assembly Bottom")
	)
	(footprint ""
		(layer "F.Cu")
		(at 39.42207 -13.379958)
		(property "Reference" "J2"
			(at -3.7719 -3.470148 0)
			(unlocked yes)
			(layer "F.SilkS")
			(effects
				(font
					(size 0.7874 0.5842)
					(thickness 0.1524)
				)
				(justify left)
			)
		)
		(property "Value" ""
			(at 0 0 0)
			(layer "F.Fab")
			(effects
				(font
					(size 1.27 1.27)
				)
			)
		)
		(duplicate_pad_numbers_are_jumpers no)
		(fp_line
			(start -3.700018 -1.952752)
			(end -3.700018 0.3175)
			(stroke
				(width 0.1524)
				(type default)
			)
			(layer "F.SilkS")
		)
		(fp_line
			(start -3.700018 3.683)
			(end -3.700018 13.780008)
			(stroke
				(width 0.1524)
				(type default)
			)
			(layer "F.SilkS")
		)
		(fp_line
			(start -3.700018 13.780008)
			(end 10.700004 13.780008)
			(stroke
				(width 0.1524)
				(type default)
			)
			(layer "F.SilkS")
		)
		(fp_line
			(start 0.350774 -2.720086)
			(end -2.489962 -2.720086)
			(stroke
				(width 0.1524)
				(type default)
			)
			(layer "F.SilkS")
		)
		(fp_line
			(start 3.49758 -2.720086)
			(end 2.034286 -2.720086)
			(stroke
				(width 0.1524)
				(type default)
			)
			(layer "F.SilkS")
		)
		(fp_line
			(start 10.700004 -2.720086)
			(end 6.785356 -2.720086)
			(stroke
				(width 0.1524)
				(type default)
			)
			(layer "F.SilkS")
		)
		(fp_line
			(start 10.700004 0.3175)
			(end 10.700004 -2.720086)
			(stroke
				(width 0.1524)
				(type default)
			)
			(layer "F.SilkS")
		)
		(fp_line
			(start 10.700004 13.780008)
			(end 10.700004 3.683)
			(stroke
				(width 0.1524)
				(type default)
			)
			(layer "F.SilkS")
		)
		(fp_poly
			(pts
				(xy -4.936998 0.508) (xy -4.936998 -0.508) (xy -3.920998 0)
			)
			(stroke
				(width 0)
				(type default)
			)
			(fill yes)
			(layer "F.SilkS")
		)
		(fp_line
			(start -3.700018 -2.720086)
			(end -3.700018 13.780008)
			(stroke
				(width 0.1)
				(type default)
			)
			(layer "F.Fab")
		)
		(fp_line
			(start -3.700018 13.780008)
			(end 10.700004 13.780008)
			(stroke
				(width 0.1)
				(type default)
			)
			(layer "F.Fab")
		)
		(fp_line
			(start 10.700004 -2.720086)
			(end -3.700018 -2.720086)
			(stroke
				(width 0.1)
				(type default)
			)
			(layer "F.Fab")
		)
		(fp_line
			(start 10.700004 13.780008)
			(end 10.700004 -2.720086)
			(stroke
				(width 0.1)
				(type default)
			)
			(layer "F.Fab")
		)
		(fp_poly
			(pts
				(xy -4.936998 0.508) (xy -4.936998 -0.508) (xy -3.920998 0)
			)
			(stroke
				(width 0)
				(type default)
			)
			(fill yes)
			(layer "F.Fab")
		)
		(pad "1" thru_hole rect
			(at 0 0 90)
			(size 1.1176 1.1176)
			(drill 0.7112)
			(layers "*.Cu" "*.Mask")
			(remove_unused_layers no)
			(net "P5V_USB_REAR")
			(clearance 0.0508)
			(thermal_gap 0.0508)
			(padstack
				(mode front_inner_back)
				(layer "Inner"
					(shape circle)
					(size 1.1176 1.1176)
					(clearance 0.0508)
				)
				(layer "B.Cu"
					(shape rect)
					(size 1.1176 1.1176)
					(clearance 0.0508)
				)
			)
		)
		(pad "2" thru_hole circle
			(at 2.500122 0 90)
			(size 1.1176 1.1176)
			(drill 0.7112)
			(layers "*.Cu" "*.Mask")
			(remove_unused_layers no)
			(net "USB2_01_F_DN")
			(clearance 0.0508)
			(thermal_gap 0.0508)
		)
		(pad "3" thru_hole circle
			(at 4.500118 0 90)
			(size 1.1176 1.1176)
			(drill 0.7112)
			(layers "*.Cu" "*.Mask")
			(remove_unused_layers no)
			(net "USB2_01_F_DP")
			(clearance 0.0508)
			(thermal_gap 0.0508)
		)
		(pad "4" thru_hole circle
			(at 6.999986 0 90)
			(size 1.1176 1.1176)
			(drill 0.7112)
			(layers "*.Cu" "*.Mask")
			(remove_unused_layers no)
			(net "GND")
			(clearance 0.0508)
			(thermal_gap 0.0508)
		)
		(pad "5" thru_hole circle
			(at 7.500112 -1.500124 90)
			(size 1.1176 1.1176)
			(drill 0.7112)
			(layers "*.Cu" "*.Mask")
			(remove_unused_layers no)
			(net "USB3_01_FB_RXN")
			(clearance 0.0508)
			(thermal_gap 0.0508)
		)
		(pad "6" thru_hole circle
			(at 5.500116 -1.500124 90)
			(size 1.1176 1.1176)
			(drill 0.7112)
			(layers "*.Cu" "*.Mask")
			(remove_unused_layers no)
			(net "USB3_01_FB_RXP")
			(clearance 0.0508)
			(thermal_gap 0.0508)
		)
		(pad "7" thru_hole circle
			(at 3.50012 -1.500124 90)
			(size 1.1176 1.1176)
			(drill 0.7112)
			(layers "*.Cu" "*.Mask")
			(remove_unused_layers no)
			(net "DEBUG_PORT_PRSNT_R")
			(clearance 0.0508)
			(thermal_gap 0.0508)
		)
		(pad "8" thru_hole circle
			(at 1.500124 -1.500124 90)
			(size 1.1176 1.1176)
			(drill 0.7112)
			(layers "*.Cu" "*.Mask")
			(remove_unused_layers no)
			(net "USB3_01_FB_TXN")
			(clearance 0.0508)
			(thermal_gap 0.0508)
		)
		(pad "9" thru_hole circle
			(at -0.499872 -1.500124 90)
			(size 1.1176 1.1176)
			(drill 0.7112)
			(layers "*.Cu" "*.Mask")
			(remove_unused_layers no)
			(net "USB3_01_FB_TXP")
			(clearance 0.0508)
			(thermal_gap 0.0508)
		)
		(pad "G1" thru_hole circle
			(at -3.070098 1.999996 90)
			(size 3.3274 3.3274)
			(drill 2.3114)
			(layers "*.Cu" "*.Mask")
			(remove_unused_layers no)
			(net "GND")
			(clearance -0.254)
		)
		(pad "G2" thru_hole circle
			(at 10.070084 1.999996 90)
			(size 3.3274 3.3274)
			(drill 2.3114)
			(layers "*.Cu" "*.Mask")
			(remove_unused_layers no)
			(net "GND")
			(clearance -0.254)
		)
	)
)
